(kicad_pcb
	(version 20260206)
	(generator "pcbnew")
	(generator_version "10.0")
	(general
		(thickness 1.6)
		(legacy_teardrops no)
	)
	(paper "A4")
	(title_block
		(title "01162023_DA0F0TEBIF0_F0T_Expander_BD_F_brd_V02_OCP.brd")
		(comment 1 "Grand Teton / footprints 2215-2220 of 9728")
	)
	(layers
		(0 "F.Cu" signal "TOP")
		(4 "In1.Cu" signal "GND")
		(6 "In2.Cu" signal "VCC")
		(8 "In3.Cu" signal "VCC1")
		(10 "In4.Cu" signal "GND1")
		(12 "In5.Cu" signal "IN1")
		(14 "In6.Cu" signal "GND2")
		(16 "In7.Cu" signal "IN2")
		(18 "In8.Cu" signal "GND3")
		(20 "In9.Cu" signal "IN3")
		(22 "In10.Cu" signal "GND4")
		(24 "In11.Cu" signal "IN4")
		(26 "In12.Cu" signal "GND5")
		(28 "In13.Cu" signal "IN5")
		(30 "In14.Cu" signal "GND6")
		(32 "In15.Cu" signal "IN6")
		(34 "In16.Cu" signal "GND7")
		(2 "B.Cu" signal "BOTTOM")
		(9 "F.Adhes" user "F.Adhesive")
		(11 "B.Adhes" user "B.Adhesive")
		(13 "F.Paste" user "Package Geometry/Pastemask Top")
		(15 "B.Paste" user "Package Geometry/Pastemask Bottom")
		(5 "F.SilkS" user "Ref Des/Silkscreen Top")
		(7 "B.SilkS" user "Ref Des/Silkscreen Bottom")
		(1 "F.Mask" user "Board Geometry/Soldermask Top")
		(3 "B.Mask" user "Board Geometry/Soldermask Bottom")
		(17 "Dwgs.User" user "User.Drawings")
		(19 "Cmts.User" user "User.Comments")
		(21 "Eco1.User" user "User.Eco1")
		(23 "Eco2.User" user "User.Eco2")
		(25 "Edge.Cuts" user "Board Geometry/Outline")
		(27 "Margin" user)
		(31 "F.CrtYd" user "Package Geometry/Place Bound Top")
		(29 "B.CrtYd" user "Package Geometry/Place Bound Bottom")
		(35 "F.Fab" user "Ref Des/Assembly Top")
		(33 "B.Fab" user "Ref Des/Assembly Bottom")
	)
	(footprint ""
		(layer "F.Cu")
		(at 368.574066 -72.766682 90)
		(property "Reference" "PR7087"
			(at 0 0 90)
			(layer "F.SilkS")
			(hide yes)
			(effects
				(font
					(size 1.27 1.27)
				)
			)
		)
		(property "Value" ""
			(at 0 0 90)
			(layer "F.Fab")
			(effects
				(font
					(size 1.27 1.27)
				)
			)
		)
		(duplicate_pad_numbers_are_jumpers no)
		(fp_line
			(start 0.7874 -0.4064)
			(end 0.7874 0.4064)
			(stroke
				(width 0.1524)
				(type default)
			)
			(layer "F.SilkS")
		)
		(fp_line
			(start -0.7874 -0.4064)
			(end 0.7874 -0.4064)
			(stroke
				(width 0.1524)
				(type default)
			)
			(layer "F.SilkS")
		)
		(fp_line
			(start 0.7874 0.4064)
			(end -0.7874 0.4064)
			(stroke
				(width 0.1524)
				(type default)
			)
			(layer "F.SilkS")
		)
		(fp_line
			(start -0.7874 0.4064)
			(end -0.7874 -0.4064)
			(stroke
				(width 0.1524)
				(type default)
			)
			(layer "F.SilkS")
		)
		(fp_line
			(start -0.12065 -0.305054)
			(end -0.12065 -0.2794)
			(stroke
				(width 0.1)
				(type default)
			)
			(layer "F.Fab")
		)
		(fp_line
			(start -0.67945 -0.305054)
			(end -0.12065 -0.305054)
			(stroke
				(width 0.1)
				(type default)
			)
			(layer "F.Fab")
		)
		(fp_line
			(start 0.67945 -0.3048)
			(end 0.67945 0.3048)
			(stroke
				(width 0.1)
				(type default)
			)
			(layer "F.Fab")
		)
		(fp_line
			(start 0.12065 -0.3048)
			(end 0.67945 -0.3048)
			(stroke
				(width 0.1)
				(type default)
			)
			(layer "F.Fab")
		)
		(fp_line
			(start 0.12065 -0.2794)
			(end 0.12065 -0.3048)
			(stroke
				(width 0.1)
				(type default)
			)
			(layer "F.Fab")
		)
		(fp_line
			(start -0.12065 -0.2794)
			(end 0.12065 -0.2794)
			(stroke
				(width 0.1)
				(type default)
			)
			(layer "F.Fab")
		)
		(fp_line
			(start 0.120396 0.2794)
			(end -0.12065 0.2794)
			(stroke
				(width 0.1)
				(type default)
			)
			(layer "F.Fab")
		)
		(fp_line
			(start -0.12065 0.2794)
			(end -0.12065 0.3048)
			(stroke
				(width 0.1)
				(type default)
			)
			(layer "F.Fab")
		)
		(fp_line
			(start 0.67945 0.3048)
			(end 0.120396 0.3048)
			(stroke
				(width 0.1)
				(type default)
			)
			(layer "F.Fab")
		)
		(fp_line
			(start 0.120396 0.3048)
			(end 0.120396 0.2794)
			(stroke
				(width 0.1)
				(type default)
			)
			(layer "F.Fab")
		)
		(fp_line
			(start -0.12065 0.3048)
			(end -0.67945 0.3048)
			(stroke
				(width 0.1)
				(type default)
			)
			(layer "F.Fab")
		)
		(fp_line
			(start -0.67945 0.3048)
			(end -0.67945 -0.305054)
			(stroke
				(width 0.1)
				(type default)
			)
			(layer "F.Fab")
		)
		(pad "1" smd circle
			(at -0.40005 0 90)
			(size 0 0)
			(layers "F.Cu" "F.Mask" "F.Paste")
			(net "P12V_SSD12_CO_MODE")
		)
		(pad "2" smd circle
			(at 0.40005 0 90)
			(size 0 0)
			(layers "F.Cu" "F.Mask" "F.Paste")
			(net "GND")
		)
	)
	(footprint ""
		(layer "F.Cu")
		(at 125.349 -279.486868 -90)
		(property "Reference" "PC89"
			(at 0 0 270)
			(layer "F.SilkS")
			(hide yes)
			(effects
				(font
					(size 1.27 1.27)
				)
			)
		)
		(property "Value" ""
			(at 0 0 270)
			(layer "F.Fab")
			(effects
				(font
					(size 1.27 1.27)
				)
			)
		)
		(duplicate_pad_numbers_are_jumpers no)
		(fp_line
			(start -0.7874 0.4064)
			(end -0.7874 -0.4064)
			(stroke
				(width 0.1524)
				(type default)
			)
			(layer "F.SilkS")
		)
		(fp_line
			(start 0.7874 0.4064)
			(end -0.7874 0.4064)
			(stroke
				(width 0.1524)
				(type default)
			)
			(layer "F.SilkS")
		)
		(fp_line
			(start -0.7874 -0.4064)
			(end 0.7874 -0.4064)
			(stroke
				(width 0.1524)
				(type default)
			)
			(layer "F.SilkS")
		)
		(fp_line
			(start 0.7874 -0.4064)
			(end 0.7874 0.4064)
			(stroke
				(width 0.1524)
				(type default)
			)
			(layer "F.SilkS")
		)
		(fp_line
			(start -0.67945 0.3048)
			(end -0.67945 -0.305054)
			(stroke
				(width 0.1)
				(type default)
			)
			(layer "F.Fab")
		)
		(fp_line
			(start -0.12065 0.3048)
			(end -0.67945 0.3048)
			(stroke
				(width 0.1)
				(type default)
			)
			(layer "F.Fab")
		)
		(fp_line
			(start 0.120396 0.3048)
			(end 0.120396 0.2794)
			(stroke
				(width 0.1)
				(type default)
			)
			(layer "F.Fab")
		)
		(fp_line
			(start 0.67945 0.3048)
			(end 0.120396 0.3048)
			(stroke
				(width 0.1)
				(type default)
			)
			(layer "F.Fab")
		)
		(fp_line
			(start -0.12065 0.2794)
			(end -0.12065 0.3048)
			(stroke
				(width 0.1)
				(type default)
			)
			(layer "F.Fab")
		)
		(fp_line
			(start 0.120396 0.2794)
			(end -0.12065 0.2794)
			(stroke
				(width 0.1)
				(type default)
			)
			(layer "F.Fab")
		)
		(fp_line
			(start -0.12065 -0.2794)
			(end 0.12065 -0.2794)
			(stroke
				(width 0.1)
				(type default)
			)
			(layer "F.Fab")
		)
		(fp_line
			(start 0.12065 -0.2794)
			(end 0.12065 -0.3048)
			(stroke
				(width 0.1)
				(type default)
			)
			(layer "F.Fab")
		)
		(fp_line
			(start 0.12065 -0.3048)
			(end 0.67945 -0.3048)
			(stroke
				(width 0.1)
				(type default)
			)
			(layer "F.Fab")
		)
		(fp_line
			(start 0.67945 -0.3048)
			(end 0.67945 0.3048)
			(stroke
				(width 0.1)
				(type default)
			)
			(layer "F.Fab")
		)
		(fp_line
			(start -0.67945 -0.305054)
			(end -0.12065 -0.305054)
			(stroke
				(width 0.1)
				(type default)
			)
			(layer "F.Fab")
		)
		(fp_line
			(start -0.12065 -0.305054)
			(end -0.12065 -0.2794)
			(stroke
				(width 0.1)
				(type default)
			)
			(layer "F.Fab")
		)
		(pad "1" smd circle
			(at -0.40005 0 270)
			(size 0 0)
			(layers "F.Cu" "F.Mask" "F.Paste")
			(net "P0V8_PEX0_VREF")
		)
		(pad "2" smd circle
			(at 0.40005 0 270)
			(size 0 0)
			(layers "F.Cu" "F.Mask" "F.Paste")
			(net "GND")
		)
	)
	(footprint ""
		(layer "F.Cu")
		(at 194.343782 -46.90491)
		(property "Reference" "R576"
			(at 0 0 0)
			(layer "F.SilkS")
			(hide yes)
			(effects
				(font
					(size 1.27 1.27)
				)
			)
		)
		(property "Value" ""
			(at 0 0 0)
			(layer "F.Fab")
			(effects
				(font
					(size 1.27 1.27)
				)
			)
		)
		(duplicate_pad_numbers_are_jumpers no)
		(fp_line
			(start -0.7874 -0.4064)
			(end 0.7874 -0.4064)
			(stroke
				(width 0.1524)
				(type default)
			)
			(layer "F.SilkS")
		)
		(fp_line
			(start -0.7874 0.4064)
			(end -0.7874 -0.4064)
			(stroke
				(width 0.1524)
				(type default)
			)
			(layer "F.SilkS")
		)
		(fp_line
			(start 0.7874 -0.4064)
			(end 0.7874 0.4064)
			(stroke
				(width 0.1524)
				(type default)
			)
			(layer "F.SilkS")
		)
		(fp_line
			(start 0.7874 0.4064)
			(end -0.7874 0.4064)
			(stroke
				(width 0.1524)
				(type default)
			)
			(layer "F.SilkS")
		)
		(fp_line
			(start -0.67945 -0.305054)
			(end -0.12065 -0.305054)
			(stroke
				(width 0.1)
				(type default)
			)
			(layer "F.Fab")
		)
		(fp_line
			(start -0.67945 0.3048)
			(end -0.67945 -0.305054)
			(stroke
				(width 0.1)
				(type default)
			)
			(layer "F.Fab")
		)
		(fp_line
			(start -0.12065 -0.305054)
			(end -0.12065 -0.2794)
			(stroke
				(width 0.1)
				(type default)
			)
			(layer "F.Fab")
		)
		(fp_line
			(start -0.12065 -0.2794)
			(end 0.12065 -0.2794)
			(stroke
				(width 0.1)
				(type default)
			)
			(layer "F.Fab")
		)
		(fp_line
			(start -0.12065 0.2794)
			(end -0.12065 0.3048)
			(stroke
				(width 0.1)
				(type default)
			)
			(layer "F.Fab")
		)
		(fp_line
			(start -0.12065 0.3048)
			(end -0.67945 0.3048)
			(stroke
				(width 0.1)
				(type default)
			)
			(layer "F.Fab")
		)
		(fp_line
			(start 0.120396 0.2794)
			(end -0.12065 0.2794)
			(stroke
				(width 0.1)
				(type default)
			)
			(layer "F.Fab")
		)
		(fp_line
			(start 0.120396 0.3048)
			(end 0.120396 0.2794)
			(stroke
				(width 0.1)
				(type default)
			)
			(layer "F.Fab")
		)
		(fp_line
			(start 0.12065 -0.3048)
			(end 0.67945 -0.3048)
			(stroke
				(width 0.1)
				(type default)
			)
			(layer "F.Fab")
		)
		(fp_line
			(start 0.12065 -0.2794)
			(end 0.12065 -0.3048)
			(stroke
				(width 0.1)
				(type default)
			)
			(layer "F.Fab")
		)
		(fp_line
			(start 0.67945 -0.3048)
			(end 0.67945 0.3048)
			(stroke
				(width 0.1)
				(type default)
			)
			(layer "F.Fab")
		)
		(fp_line
			(start 0.67945 0.3048)
			(end 0.120396 0.3048)
			(stroke
				(width 0.1)
				(type default)
			)
			(layer "F.Fab")
		)
		(pad "1" smd circle
			(at -0.40005 0)
			(size 0 0)
			(layers "F.Cu" "F.Mask" "F.Paste")
			(net "SSD6_ADC_ALERT_N")
		)
		(pad "2" smd circle
			(at 0.40005 0)
			(size 0 0)
			(layers "F.Cu" "F.Mask" "F.Paste")
			(net "SSD_0_7_ADC_ALERT_N")
		)
	)
	(footprint ""
		(layer "F.Cu")
		(at 332.846934 -54.3941)
		(property "Reference" "PU44"
			(at -1.964182 2.975356 0)
			(unlocked yes)
			(layer "F.SilkS")
			(effects
				(font
					(size 0.7874 0.5842)
					(thickness 0.1524)
				)
				(justify left)
			)
		)
		(property "Value" ""
			(at 0 0 0)
			(layer "F.Fab")
			(effects
				(font
					(size 1.27 1.27)
				)
			)
		)
		(duplicate_pad_numbers_are_jumpers no)
		(fp_line
			(start -1.943608 -1.549908)
			(end 1.943608 -1.549908)
			(stroke
				(width 0.1524)
				(type default)
			)
			(layer "F.SilkS")
		)
		(fp_line
			(start -1.943608 1.549908)
			(end -1.943608 -1.549908)
			(stroke
				(width 0.1524)
				(type default)
			)
			(layer "F.SilkS")
		)
		(fp_line
			(start 1.943608 -1.549908)
			(end 1.943608 1.549908)
			(stroke
				(width 0.1524)
				(type default)
			)
			(layer "F.SilkS")
		)
		(fp_line
			(start 1.943608 1.549908)
			(end -1.943608 1.549908)
			(stroke
				(width 0.1524)
				(type default)
			)
			(layer "F.SilkS")
		)
		(fp_poly
			(pts
				(xy -2.019808 -1.549908) (xy -1.257808 -1.549908) (xy -1.257808 -1.880108) (xy -2.019808 -1.880108)
			)
			(stroke
				(width 0)
				(type default)
			)
			(fill yes)
			(layer "F.SilkS")
		)
		(fp_line
			(start -1.549908 -1.549908)
			(end 1.549908 -1.549908)
			(stroke
				(width 0.1)
				(type default)
			)
			(layer "F.Fab")
		)
		(fp_line
			(start -1.549908 1.549908)
			(end -1.549908 -1.549908)
			(stroke
				(width 0.1)
				(type default)
			)
			(layer "F.Fab")
		)
		(fp_line
			(start 1.549908 -1.549908)
			(end 1.549908 1.549908)
			(stroke
				(width 0.1)
				(type default)
			)
			(layer "F.Fab")
		)
		(fp_line
			(start 1.549908 1.549908)
			(end -1.549908 1.549908)
			(stroke
				(width 0.1)
				(type default)
			)
			(layer "F.Fab")
		)
		(fp_poly
			(pts
				(xy -2.019808 -1.549908) (xy -1.257808 -1.549908) (xy -1.257808 -1.880108) (xy -2.019808 -1.880108)
			)
			(stroke
				(width 0)
				(type default)
			)
			(fill yes)
			(layer "F.Fab")
		)
		(pad "1" smd rect
			(at -1.500124 -1.249934 270)
			(size 0.2794 0.6096)
			(layers "F.Cu" "F.Mask" "F.Paste")
			(net "P12V_SSD11_R")
		)
		(pad "2" smd rect
			(at -1.500124 -0.750062 270)
			(size 0.2794 0.6096)
			(layers "F.Cu" "F.Mask" "F.Paste")
			(net "P12V_SSD11_R")
		)
		(pad "3" smd rect
			(at -1.500124 -0.249936 270)
			(size 0.2794 0.6096)
			(layers "F.Cu" "F.Mask" "F.Paste")
			(net "P12V_SSD11_R")
		)
		(pad "4" smd rect
			(at -1.500124 0.249936 270)
			(size 0.2794 0.6096)
			(layers "F.Cu" "F.Mask" "F.Paste")
			(net "P12V_SSD11_R")
		)
		(pad "5" smd rect
			(at -1.500124 0.750062 270)
			(size 0.2794 0.6096)
			(layers "F.Cu" "F.Mask" "F.Paste")
			(net "P12V_SSD11_R")
		)
		(pad "6" smd rect
			(at -1.500124 1.249934 270)
			(size 0.2794 0.6096)
			(layers "F.Cu" "F.Mask" "F.Paste")
			(net "GND")
		)
		(pad "7" smd rect
			(at 1.500124 1.249934 270)
			(size 0.2794 0.6096)
			(layers "F.Cu" "F.Mask" "F.Paste")
			(net "P12V_SSD11_SS")
		)
		(pad "8" smd rect
			(at 1.500124 0.750062 270)
			(size 0.2794 0.6096)
			(layers "F.Cu" "F.Mask" "F.Paste")
			(net "PWRGD_P12V_SSD11")
		)
		(pad "9" smd rect
			(at 1.500124 0.249936 270)
			(size 0.2794 0.6096)
			(layers "F.Cu" "F.Mask" "F.Paste")
			(net "P12V_SSD11_OCP")
		)
		(pad "10" smd rect
			(at 1.500124 -0.249936 270)
			(size 0.2794 0.6096)
			(layers "F.Cu" "F.Mask" "F.Paste")
			(net "P5V_AUX")
		)
		(pad "11" smd rect
			(at 1.500124 -0.750062 270)
			(size 0.2794 0.6096)
			(layers "F.Cu" "F.Mask" "F.Paste")
			(net "SSD11_PWR_EN_R")
		)
		(pad "12" smd rect
			(at 1.500124 -1.249934 270)
			(size 0.2794 0.6096)
			(layers "F.Cu" "F.Mask" "F.Paste")
			(net "P12V_AUX")
		)
		(pad "13" smd rect
			(at 0 0)
			(size 1.9812 2.7178)
			(layers "F.Cu" "F.Mask" "F.Paste")
			(net "P12V_AUX")
		)
		(zone
			(layer "F.Cu")
			(hatch none 0.5)
			(connect_pads
				(clearance 0)
			)
			(min_thickness 0.25)
			(keepout
				(tracks not_allowed)
				(vias allowed)
				(pads allowed)
				(copperpour not_allowed)
				(footprints allowed)
			)
			(placement
				(enabled no)
				(sheetname "")
			)
			(fill
				(thermal_gap 0.5)
				(thermal_bridge_width 0.5)
				(island_removal_mode 0)
			)
			(polygon
				(pts
					(xy 333.989934 -55.9435) (xy 333.989934 -55.8165) (xy 333.989934 -52.8447) (xy 333.989934 -52.844192)
					(xy 331.703934 -52.844192) (xy 331.703934 -52.8447) (xy 331.703934 -52.9717) (xy 331.703934 -54.3941)
					(xy 331.805534 -54.3941) (xy 331.805534 -52.9717) (xy 333.888334 -52.9717) (xy 333.888334 -55.8165)
					(xy 331.805534 -55.8165) (xy 331.805534 -54.4195) (xy 331.703934 -54.4195) (xy 331.703934 -55.8165)
					(xy 331.703934 -55.9435) (xy 331.703934 -55.944008) (xy 333.989934 -55.944008)
				)
			)
		)
	)
	(footprint ""
		(layer "F.Cu")
		(at 355.223318 -205.160118 90)
		(property "Reference" "R6418"
			(at 0 0 90)
			(layer "F.SilkS")
			(hide yes)
			(effects
				(font
					(size 1.27 1.27)
				)
			)
		)
		(property "Value" ""
			(at 0 0 90)
			(layer "F.Fab")
			(effects
				(font
					(size 1.27 1.27)
				)
			)
		)
		(duplicate_pad_numbers_are_jumpers no)
		(fp_line
			(start 0.7874 -0.4064)
			(end 0.7874 0.4064)
			(stroke
				(width 0.1524)
				(type default)
			)
			(layer "F.SilkS")
		)
		(fp_line
			(start -0.7874 -0.4064)
			(end 0.7874 -0.4064)
			(stroke
				(width 0.1524)
				(type default)
			)
			(layer "F.SilkS")
		)
		(fp_line
			(start 0.7874 0.4064)
			(end -0.7874 0.4064)
			(stroke
				(width 0.1524)
				(type default)
			)
			(layer "F.SilkS")
		)
		(fp_line
			(start -0.7874 0.4064)
			(end -0.7874 -0.4064)
			(stroke
				(width 0.1524)
				(type default)
			)
			(layer "F.SilkS")
		)
		(fp_line
			(start -0.12065 -0.305054)
			(end -0.12065 -0.2794)
			(stroke
				(width 0.1)
				(type default)
			)
			(layer "F.Fab")
		)
		(fp_line
			(start -0.67945 -0.305054)
			(end -0.12065 -0.305054)
			(stroke
				(width 0.1)
				(type default)
			)
			(layer "F.Fab")
		)
		(fp_line
			(start 0.67945 -0.3048)
			(end 0.67945 0.3048)
			(stroke
				(width 0.1)
				(type default)
			)
			(layer "F.Fab")
		)
		(fp_line
			(start 0.12065 -0.3048)
			(end 0.67945 -0.3048)
			(stroke
				(width 0.1)
				(type default)
			)
			(layer "F.Fab")
		)
		(fp_line
			(start 0.12065 -0.2794)
			(end 0.12065 -0.3048)
			(stroke
				(width 0.1)
				(type default)
			)
			(layer "F.Fab")
		)
		(fp_line
			(start -0.12065 -0.2794)
			(end 0.12065 -0.2794)
			(stroke
				(width 0.1)
				(type default)
			)
			(layer "F.Fab")
		)
		(fp_line
			(start 0.120396 0.2794)
			(end -0.12065 0.2794)
			(stroke
				(width 0.1)
				(type default)
			)
			(layer "F.Fab")
		)
		(fp_line
			(start -0.12065 0.2794)
			(end -0.12065 0.3048)
			(stroke
				(width 0.1)
				(type default)
			)
			(layer "F.Fab")
		)
		(fp_line
			(start 0.67945 0.3048)
			(end 0.120396 0.3048)
			(stroke
				(width 0.1)
				(type default)
			)
			(layer "F.Fab")
		)
		(fp_line
			(start 0.120396 0.3048)
			(end 0.120396 0.2794)
			(stroke
				(width 0.1)
				(type default)
			)
			(layer "F.Fab")
		)
		(fp_line
			(start -0.12065 0.3048)
			(end -0.67945 0.3048)
			(stroke
				(width 0.1)
				(type default)
			)
			(layer "F.Fab")
		)
		(fp_line
			(start -0.67945 0.3048)
			(end -0.67945 -0.305054)
			(stroke
				(width 0.1)
				(type default)
			)
			(layer "F.Fab")
		)
		(pad "1" smd circle
			(at -0.40005 0 90)
			(size 0 0)
			(layers "F.Cu" "F.Mask" "F.Paste")
			(net "FPGA_PEX1_MODE_SEL2_R")
		)
		(pad "2" smd circle
			(at 0.40005 0 90)
			(size 0 0)
			(layers "F.Cu" "F.Mask" "F.Paste")
			(net "FPGA_PEX1_MODE_SEL2")
		)
	)
	(footprint ""
		(layer "F.Cu")
		(at 196.452236 -107.552998 -90)
		(property "Reference" "C891"
			(at 0 0 270)
			(layer "F.SilkS")
			(hide yes)
			(effects
				(font
					(size 1.27 1.27)
				)
			)
		)
		(property "Value" ""
			(at 0 0 270)
			(layer "F.Fab")
			(effects
				(font
					(size 1.27 1.27)
				)
			)
		)
		(duplicate_pad_numbers_are_jumpers no)
		(fp_line
			(start -1.524 0.762)
			(end -1.524 -0.762)
			(stroke
				(width 0.1524)
				(type default)
			)
			(layer "F.SilkS")
		)
		(fp_line
			(start 1.524 0.762)
			(end -1.524 0.762)
			(stroke
				(width 0.1524)
				(type default)
			)
			(layer "F.SilkS")
		)
		(fp_line
			(start -1.524 -0.762)
			(end 1.524 -0.762)
			(stroke
				(width 0.1524)
				(type default)
			)
			(layer "F.SilkS")
		)
		(fp_line
			(start 1.524 -0.762)
			(end 1.524 0.762)
			(stroke
				(width 0.1524)
				(type default)
			)
			(layer "F.SilkS")
		)
		(fp_line
			(start -1.1049 0.724916)
			(end 1.1049 0.724916)
			(stroke
				(width 0.1)
				(type default)
			)
			(layer "F.Fab")
		)
		(fp_line
			(start 1.1049 0.724916)
			(end 1.1049 -0.724916)
			(stroke
				(width 0.1)
				(type default)
			)
			(layer "F.Fab")
		)
		(fp_line
			(start -1.1049 -0.724916)
			(end -1.1049 0.724916)
			(stroke
				(width 0.1)
				(type default)
			)
			(layer "F.Fab")
		)
		(fp_line
			(start 1.1049 -0.724916)
			(end -1.1049 -0.724916)
			(stroke
				(width 0.1)
				(type default)
			)
			(layer "F.Fab")
		)
		(pad "1" smd rect
			(at -0.889 0 90)
			(size 1.016 1.27)
			(layers "F.Cu" "F.Mask" "F.Paste")
			(net "P12V_NIC3")
		)
		(pad "2" smd rect
			(at 0.889 0 90)
			(size 1.016 1.27)
			(layers "F.Cu" "F.Mask" "F.Paste")
			(net "GND")
		)
	)
)
